# SCM (Grand Teton) — schematic netlist excerpt (pin names and nets, part order shuffled) for the footprints in the layout excerpt that follows; sources: Cadence DE-HDL packaged netlist, KiCad conversion of 12092022_DA0F0TMDCD0_F0T_Management_Board_D_brd_V3_OCP.brd

L13  Q_INDUCTOR  BLM18PG121SN1D/2000MA IND  pkg SMLF  page 17 : \1\ = P1V0_AUX ; \2\ = P1V0_STBY_PE_VCC10A
R4  Q_RES  1K 1% CHIP  pkg 0402LF  page 20 : A = PD_M_BMC_DDR4_PAR ; B = GND

(kicad_pcb
	(version 20260206)
	(generator "pcbnew")
	(generator_version "10.0")
	(general
		(thickness 1.6)
		(legacy_teardrops no)
	)
	(paper "A4")
	(title_block
		(title "12092022_DA0F0TMDCD0_F0T_Management_Board_D_brd_V3_OCP.brd")
		(comment 1 "Grand Teton / footprints 1068-1069 of 1440")
	)
	(layers
		(0 "F.Cu" signal "TOP")
		(4 "In1.Cu" signal "GND")
		(6 "In2.Cu" signal "IN1")
		(8 "In3.Cu" signal "GND1")
		(10 "In4.Cu" signal "IN2")
		(12 "In5.Cu" signal "VCC")
		(14 "In6.Cu" signal "VCC1")
		(16 "In7.Cu" signal "IN3")
		(18 "In8.Cu" signal "GND2")
		(20 "In9.Cu" signal "IN4")
		(22 "In10.Cu" signal "GND3")
		(2 "B.Cu" signal "BOTTOM")
		(9 "F.Adhes" user "F.Adhesive")
		(11 "B.Adhes" user "B.Adhesive")
		(13 "F.Paste" user "Package Geometry/Pastemask Top")
		(15 "B.Paste" user "Package Geometry/Pastemask Bottom")
		(5 "F.SilkS" user "Ref Des/Silkscreen Top")
		(7 "B.SilkS" user "Ref Des/Silkscreen Bottom")
		(1 "F.Mask" user "Board Geometry/Soldermask Top")
		(3 "B.Mask" user "Board Geometry/Soldermask Bottom")
		(17 "Dwgs.User" user "User.Drawings")
		(19 "Cmts.User" user "User.Comments")
		(21 "Eco1.User" user "User.Eco1")
		(23 "Eco2.User" user "User.Eco2")
		(25 "Edge.Cuts" user "Board Geometry/Outline")
		(27 "Margin" user)
		(31 "F.CrtYd" user "Package Geometry/Place Bound Top")
		(29 "B.CrtYd" user "Package Geometry/Place Bound Bottom")
		(35 "F.Fab" user "Ref Des/Assembly Top")
		(33 "B.Fab" user "Ref Des/Assembly Bottom")
	)
	(footprint ""
		(layer "B.Cu")
		(at 72.909176 -42.113708)
		(property "Reference" "R4"
			(at 0 0 0)
			(layer "B.SilkS")
			(hide yes)
			(effects
				(font
					(size 1.27 1.27)
				)
				(justify mirror)
			)
		)
		(property "Value" ""
			(at 0 0 0)
			(layer "B.Fab")
			(effects
				(font
					(size 1.27 1.27)
				)
				(justify mirror)
			)
		)
		(duplicate_pad_numbers_are_jumpers no)
		(fp_line
			(start -0.7874 -0.4064)
			(end -0.7874 0.4064)
			(stroke
				(width 0.1524)
				(type default)
			)
			(layer "B.SilkS")
		)
		(fp_line
			(start -0.7874 0.4064)
			(end 0.7874 0.4064)
			(stroke
				(width 0.1524)
				(type default)
			)
			(layer "B.SilkS")
		)
		(fp_line
			(start 0.7874 -0.4064)
			(end -0.7874 -0.4064)
			(stroke
				(width 0.1524)
				(type default)
			)
			(layer "B.SilkS")
		)
		(fp_line
			(start 0.7874 0.4064)
			(end 0.7874 -0.4064)
			(stroke
				(width 0.1524)
				(type default)
			)
			(layer "B.SilkS")
		)
		(fp_line
			(start -0.67945 -0.3048)
			(end -0.67945 0.3048)
			(stroke
				(width 0.1)
				(type default)
			)
			(layer "B.Fab")
		)
		(fp_line
			(start -0.67945 0.3048)
			(end -0.120396 0.3048)
			(stroke
				(width 0.1)
				(type default)
			)
			(layer "B.Fab")
		)
		(fp_line
			(start -0.12065 -0.3048)
			(end -0.67945 -0.3048)
			(stroke
				(width 0.1)
				(type default)
			)
			(layer "B.Fab")
		)
		(fp_line
			(start -0.12065 -0.2794)
			(end -0.12065 -0.3048)
			(stroke
				(width 0.1)
				(type default)
			)
			(layer "B.Fab")
		)
		(fp_line
			(start -0.120396 0.2794)
			(end 0.12065 0.2794)
			(stroke
				(width 0.1)
				(type default)
			)
			(layer "B.Fab")
		)
		(fp_line
			(start -0.120396 0.3048)
			(end -0.120396 0.2794)
			(stroke
				(width 0.1)
				(type default)
			)
			(layer "B.Fab")
		)
		(fp_line
			(start 0.12065 -0.305054)
			(end 0.12065 -0.2794)
			(stroke
				(width 0.1)
				(type default)
			)
			(layer "B.Fab")
		)
		(fp_line
			(start 0.12065 -0.2794)
			(end -0.12065 -0.2794)
			(stroke
				(width 0.1)
				(type default)
			)
			(layer "B.Fab")
		)
		(fp_line
			(start 0.12065 0.2794)
			(end 0.12065 0.3048)
			(stroke
				(width 0.1)
				(type default)
			)
			(layer "B.Fab")
		)
		(fp_line
			(start 0.12065 0.3048)
			(end 0.67945 0.3048)
			(stroke
				(width 0.1)
				(type default)
			)
			(layer "B.Fab")
		)
		(fp_line
			(start 0.67945 -0.305054)
			(end 0.12065 -0.305054)
			(stroke
				(width 0.1)
				(type default)
			)
			(layer "B.Fab")
		)
		(fp_line
			(start 0.67945 0.3048)
			(end 0.67945 -0.305054)
			(stroke
				(width 0.1)
				(type default)
			)
			(layer "B.Fab")
		)
		(pad "1" smd circle
			(at 0.40005 0 180)
			(size 0 0)
			(layers "B.Cu" "B.Mask" "B.Paste")
			(net "PD_M_BMC_DDR4_PAR")
		)
		(pad "2" smd circle
			(at -0.40005 0 180)
			(size 0 0)
			(layers "B.Cu" "B.Mask" "B.Paste")
			(net "GND")
		)
	)
	(footprint ""
		(layer "B.Cu")
		(at 72.003412 -58.051954 -90)
		(property "Reference" "L13"
			(at 0 0 90)
			(layer "B.SilkS")
			(hide yes)
			(effects
				(font
					(size 1.27 1.27)
				)
				(justify mirror)
			)
		)
		(property "Value" ""
			(at 0 0 90)
			(layer "B.Fab")
			(effects
				(font
					(size 1.27 1.27)
				)
				(justify mirror)
			)
		)
		(duplicate_pad_numbers_are_jumpers no)
		(fp_line
			(start -1.27 0.5842)
			(end 1.27 0.5842)
			(stroke
				(width 0.1524)
				(type default)
			)
			(layer "B.SilkS")
		)
		(fp_line
			(start -1.27 0.5842)
			(end -1.27 -0.5842)
			(stroke
				(width 0.1524)
				(type default)
			)
			(layer "B.SilkS")
		)
		(fp_line
			(start -0.127 0.5842)
			(end -0.127 -0.5842)
			(stroke
				(width 0.1524)
				(type default)
			)
			(layer "B.SilkS")
		)
		(fp_line
			(start 0.127 0.5842)
			(end 0.127 -0.5842)
			(stroke
				(width 0.1524)
				(type default)
			)
			(layer "B.SilkS")
		)
		(fp_line
			(start 1.27 0.5842)
			(end 1.27 -0.5842)
			(stroke
				(width 0.1524)
				(type default)
			)
			(layer "B.SilkS")
		)
		(fp_line
			(start 1.27 -0.5588)
			(end 1.27 -0.5842)
			(stroke
				(width 0.1524)
				(type default)
			)
			(layer "B.SilkS")
		)
		(fp_line
			(start 1.27 -0.5842)
			(end -1.27 -0.5842)
			(stroke
				(width 0.1524)
				(type default)
			)
			(layer "B.SilkS")
		)
		(fp_line
			(start -0.9144 0.508)
			(end 0.9144 0.508)
			(stroke
				(width 0.1)
				(type default)
			)
			(layer "B.Fab")
		)
		(fp_line
			(start 0.9144 0.508)
			(end 0.9144 0.406654)
			(stroke
				(width 0.1)
				(type default)
			)
			(layer "B.Fab")
		)
		(fp_line
			(start 0.9144 0.406654)
			(end 1.194308 0.406654)
			(stroke
				(width 0.1)
				(type default)
			)
			(layer "B.Fab")
		)
		(fp_line
			(start 1.194308 0.406654)
			(end 1.194308 -0.406654)
			(stroke
				(width 0.1)
				(type default)
			)
			(layer "B.Fab")
		)
		(fp_line
			(start -1.1938 0.4064)
			(end -0.9144 0.4064)
			(stroke
				(width 0.1)
				(type default)
			)
			(layer "B.Fab")
		)
		(fp_line
			(start -0.9144 0.4064)
			(end -0.9144 0.508)
			(stroke
				(width 0.1)
				(type default)
			)
			(layer "B.Fab")
		)
		(fp_line
			(start -1.1938 -0.406654)
			(end -1.1938 0.4064)
			(stroke
				(width 0.1)
				(type default)
			)
			(layer "B.Fab")
		)
		(fp_line
			(start -0.9144 -0.406654)
			(end -1.1938 -0.406654)
			(stroke
				(width 0.1)
				(type default)
			)
			(layer "B.Fab")
		)
		(fp_line
			(start 0.9144 -0.406654)
			(end 0.9144 -0.508)
			(stroke
				(width 0.1)
				(type default)
			)
			(layer "B.Fab")
		)
		(fp_line
			(start 1.194308 -0.406654)
			(end 0.9144 -0.406654)
			(stroke
				(width 0.1)
				(type default)
			)
			(layer "B.Fab")
		)
		(fp_line
			(start -0.9144 -0.508)
			(end -0.9144 -0.406654)
			(stroke
				(width 0.1)
				(type default)
			)
			(layer "B.Fab")
		)
		(fp_line
			(start 0.9144 -0.508)
			(end -0.9144 -0.508)
			(stroke
				(width 0.1)
				(type default)
			)
			(layer "B.Fab")
		)
		(pad "1" smd rect
			(at 0.7366 0 180)
			(size 0.7112 0.8128)
			(layers "B.Cu" "B.Mask" "B.Paste")
			(net "P1V0_AUX")
		)
		(pad "2" smd rect
			(at -0.7366 0 180)
			(size 0.7112 0.8128)
			(layers "B.Cu" "B.Mask" "B.Paste")
			(net "P1V0_STBY_PE_VCC10A")
		)
	)
)
